(kicad_pcb
	(version 20241229)
	(generator "pcbnew")
	(generator_version "9.0")
	(general
		(thickness 1.61)
		(legacy_teardrops no)
	)
	(paper "A3")
	(title_block
		(title "SO-DIMM DDR5 Tester")
		(date "2025-11-26")
		(rev "1.3.0")
		(comment 9 "footprints 389-394 of 627")
	)
	(layers
		(0 "F.Cu" signal)
		(4 "In1.Cu" power)
		(6 "In2.Cu" mixed)
		(8 "In3.Cu" power)
		(10 "In4.Cu" mixed)
		(12 "In5.Cu" power)
		(14 "In6.Cu" mixed)
		(16 "In7.Cu" power)
		(18 "In8.Cu" power)
		(20 "In9.Cu" mixed)
		(22 "In10.Cu" power)
		(2 "B.Cu" signal)
		(9 "F.Adhes" user "F.Adhesive")
		(11 "B.Adhes" user "B.Adhesive")
		(13 "F.Paste" user)
		(15 "B.Paste" user)
		(5 "F.SilkS" user "F.Silkscreen")
		(7 "B.SilkS" user "B.Silkscreen")
		(1 "F.Mask" user)
		(3 "B.Mask" user)
		(17 "Dwgs.User" user "User.Drawings")
		(19 "Cmts.User" user "User.Comments")
		(21 "Eco1.User" user "User.Eco1")
		(23 "Eco2.User" user "User.Eco2")
		(25 "Edge.Cuts" user)
		(27 "Margin" user)
		(31 "F.CrtYd" user "F.Courtyard")
		(29 "B.CrtYd" user "B.Courtyard")
		(35 "F.Fab" user)
		(33 "B.Fab" user)
	)
	(footprint "antmicro-footprints:C_0402_1005Metric"
		(layer "B.Cu")
		(at 157.4 142.4 -90)
		(descr "Capacitor SMD 0402")
		(tags "capacitor SMD 0402")
		(property "Reference" "C9"
			(at 0 0.699 90)
			(layer "B.SilkS")
			(hide yes)
			(effects
				(font
					(size 0.7 0.7)
					(thickness 0.15)
				)
				(justify left bottom mirror)
			)
		)
		(property "Value" "C_100n_0402"
			(at -1.022927 -2.155213 90)
			(layer "B.Fab")
			(effects
				(font
					(size 0.7 0.7)
					(thickness 0.15)
				)
				(justify left bottom mirror)
			)
		)
		(property "Datasheet" "https://www.murata.com/products/productdetail?partno=GRM155R61H104KE14%23"
			(at 0 0 270)
			(layer "F.Fab")
			(hide yes)
			(effects
				(font
					(size 1.27 1.27)
					(thickness 0.15)
				)
			)
		)
		(property "Author" "Antmicro"
			(at 15 299.8 0)
			(layer "B.Fab")
			(hide yes)
			(effects
				(font
					(size 1 1)
					(thickness 0.15)
				)
				(justify mirror)
			)
		)
		(property "Dielectric" "X5R"
			(at 15 299.8 0)
			(layer "B.Fab")
			(hide yes)
			(effects
				(font
					(size 1 1)
					(thickness 0.15)
				)
				(justify mirror)
			)
		)
		(property "License" "Apache-2.0"
			(at 15 299.8 0)
			(layer "B.Fab")
			(hide yes)
			(effects
				(font
					(size 1 1)
					(thickness 0.15)
				)
				(justify mirror)
			)
		)
		(property "MPN" "GRM155R61H104KE14D"
			(at 15 299.8 0)
			(layer "B.Fab")
			(hide yes)
			(effects
				(font
					(size 1 1)
					(thickness 0.15)
				)
				(justify mirror)
			)
		)
		(property "Manufacturer" "Murata"
			(at 15 299.8 0)
			(layer "B.Fab")
			(hide yes)
			(effects
				(font
					(size 1 1)
					(thickness 0.15)
				)
				(justify mirror)
			)
		)
		(property "Val" "100n"
			(at 15 299.8 0)
			(layer "B.Fab")
			(hide yes)
			(effects
				(font
					(size 1 1)
					(thickness 0.15)
				)
				(justify mirror)
			)
		)
		(property "Voltage" "50V"
			(at 15 299.8 0)
			(layer "B.Fab")
			(hide yes)
			(effects
				(font
					(size 1 1)
					(thickness 0.15)
				)
				(justify mirror)
			)
		)
		(sheetname "/DDR5 SODIMM/")
		(sheetfile "ddr5-sodimm.kicad_sch")
		(attr smd)
		(fp_rect
			(start -0.9659 0.481258)
			(end 0.9649 -0.458742)
			(stroke
				(width 0.05)
				(type solid)
			)
			(fill no)
			(layer "B.CrtYd")
		)
		(fp_line
			(start -0.499 0.25)
			(end 0.499 0.25)
			(stroke
				(width 0.15)
				(type solid)
			)
			(layer "B.Fab")
		)
		(fp_line
			(start 0.499 0.25)
			(end 0.499 -0.248)
			(stroke
				(width 0.15)
				(type solid)
			)
			(layer "B.Fab")
		)
		(fp_line
			(start -0.499 -0.248)
			(end -0.499 0.25)
			(stroke
				(width 0.15)
				(type solid)
			)
			(layer "B.Fab")
		)
		(fp_line
			(start 0.499 -0.248)
			(end -0.499 -0.248)
			(stroke
				(width 0.15)
				(type solid)
			)
			(layer "B.Fab")
		)
		(pad "1" smd roundrect
			(at -0.484 0 270)
			(size 0.59 0.64)
			(layers "B.Cu" "B.Mask" "B.Paste")
			(roundrect_rratio 0.25)
			(net 1 "GND")
			(pintype "passive")
		)
		(pad "2" smd roundrect
			(at 0.484 0 270)
			(size 0.59 0.64)
			(layers "B.Cu" "B.Mask" "B.Paste")
			(roundrect_rratio 0.25)
			(net 206 "+1V1")
			(pintype "passive")
		)
	)
	(footprint "antmicro-footprints:C_0402_1005Metric"
		(layer "B.Cu")
		(at 146.375001 183.8005 -90)
		(descr "Capacitor SMD 0402 (1005 Metric), square (rectangular) end terminal, IPC_7351 nominal, (Body size source: IPC-SM-782 page 76, https://www.pcb-3d.com/wordpress/wp-content/uploads/ipc-sm-782a_amendment_1_and_2.pdf)")
		(tags "capacitor 0402")
		(property "Reference" "C101"
			(at 0 1.17 90)
			(layer "B.SilkS")
			(hide yes)
			(effects
				(font
					(size 0.7 0.7)
					(thickness 0.15)
				)
				(justify left bottom mirror)
			)
		)
		(property "Value" "C_100n_0402"
			(at 0 -1.169 90)
			(layer "B.Fab")
			(effects
				(font
					(size 0.7 0.7)
					(thickness 0.15)
				)
				(justify left bottom mirror)
			)
		)
		(property "Datasheet" "https://www.murata.com/products/productdetail?partno=GRM155R61H104KE14%23"
			(at 0 0 270)
			(layer "F.Fab")
			(hide yes)
			(effects
				(font
					(size 1.27 1.27)
					(thickness 0.15)
				)
			)
		)
		(property "Author" "Antmicro"
			(at -37.425499 330.175501 0)
			(layer "B.Fab")
			(hide yes)
			(effects
				(font
					(size 1 1)
					(thickness 0.15)
				)
				(justify mirror)
			)
		)
		(property "Dielectric" "X5R"
			(at -37.425499 330.175501 0)
			(layer "B.Fab")
			(hide yes)
			(effects
				(font
					(size 1 1)
					(thickness 0.15)
				)
				(justify mirror)
			)
		)
		(property "License" "Apache-2.0"
			(at -37.425499 330.175501 0)
			(layer "B.Fab")
			(hide yes)
			(effects
				(font
					(size 1 1)
					(thickness 0.15)
				)
				(justify mirror)
			)
		)
		(property "MPN" "GRM155R61H104KE14D"
			(at -37.425499 330.175501 0)
			(layer "B.Fab")
			(hide yes)
			(effects
				(font
					(size 1 1)
					(thickness 0.15)
				)
				(justify mirror)
			)
		)
		(property "Manufacturer" "Murata"
			(at -37.425499 330.175501 0)
			(layer "B.Fab")
			(hide yes)
			(effects
				(font
					(size 1 1)
					(thickness 0.15)
				)
				(justify mirror)
			)
		)
		(property "Val" "100n"
			(at -37.425499 330.175501 0)
			(layer "B.Fab")
			(hide yes)
			(effects
				(font
					(size 1 1)
					(thickness 0.15)
				)
				(justify mirror)
			)
		)
		(property "Voltage" "50V"
			(at -37.425499 330.175501 0)
			(layer "B.Fab")
			(hide yes)
			(effects
				(font
					(size 1 1)
					(thickness 0.15)
				)
				(justify mirror)
			)
		)
		(sheetname "/FPGA power/")
		(sheetfile "fpga-power.kicad_sch")
		(attr smd)
		(fp_rect
			(start -0.9656 0.4572)
			(end 0.9652 -0.4828)
			(stroke
				(width 0.05)
				(type solid)
			)
			(fill no)
			(layer "B.CrtYd")
		)
		(fp_line
			(start -0.5 0.25)
			(end 0.498 0.25)
			(stroke
				(width 0.15)
				(type solid)
			)
			(layer "B.Fab")
		)
		(fp_line
			(start 0.498 0.25)
			(end 0.498 -0.248)
			(stroke
				(width 0.15)
				(type solid)
			)
			(layer "B.Fab")
		)
		(fp_line
			(start -0.5 -0.248)
			(end -0.5 0.25)
			(stroke
				(width 0.15)
				(type solid)
			)
			(layer "B.Fab")
		)
		(fp_line
			(start 0.498 -0.248)
			(end -0.5 -0.248)
			(stroke
				(width 0.15)
				(type solid)
			)
			(layer "B.Fab")
		)
		(pad "1" smd roundrect
			(at -0.5 0 180)
			(size 0.6 0.6)
			(layers "B.Cu" "B.Mask" "B.Paste")
			(roundrect_rratio 0.25)
			(net 1 "GND")
			(pintype "passive")
		)
		(pad "2" smd roundrect
			(at 0.498 0 270)
			(size 0.6 0.6)
			(layers "B.Cu" "B.Mask" "B.Paste")
			(roundrect_rratio 0.25)
			(net 187 "+1V0_MGTAVCC")
			(pintype "passive")
		)
	)
	(footprint "antmicro-footprints:R_0402_1005Metric"
		(layer "B.Cu")
		(at 196.7 171.725)
		(descr "Resistor SMD 0402")
		(tags "resistor SMD 0402")
		(property "Reference" "R156"
			(at 3.8 0.525 180)
			(layer "B.SilkS")
			(effects
				(font
					(size 0.7 0.7)
					(thickness 0.15)
				)
				(justify left bottom mirror)
			)
		)
		(property "Value" "R_0R_0402"
			(at -1.011843 -1.772047 180)
			(layer "B.Fab")
			(effects
				(font
					(size 0.7 0.7)
					(thickness 0.15)
				)
				(justify left bottom mirror)
			)
		)
		(property "Datasheet" "https://industrial.panasonic.com/cdbs/www-data/pdf/RDA0000/AOA0000C301.pdf"
			(at 0 0 0)
			(layer "F.Fab")
			(hide yes)
			(effects
				(font
					(size 1.27 1.27)
					(thickness 0.15)
				)
			)
		)
		(property "Author" "Antmicro"
			(at 0 0 0)
			(layer "B.Fab")
			(hide yes)
			(effects
				(font
					(size 1 1)
					(thickness 0.15)
				)
				(justify mirror)
			)
		)
		(property "Current" "1A"
			(at 0 0 0)
			(layer "B.Fab")
			(hide yes)
			(effects
				(font
					(size 1 1)
					(thickness 0.15)
				)
				(justify mirror)
			)
		)
		(property "License" "Apache-2.0"
			(at 0 0 0)
			(layer "B.Fab")
			(hide yes)
			(effects
				(font
					(size 1 1)
					(thickness 0.15)
				)
				(justify mirror)
			)
		)
		(property "MPN" "ERJ2GE0R00X"
			(at 0 0 0)
			(layer "B.Fab")
			(hide yes)
			(effects
				(font
					(size 1 1)
					(thickness 0.15)
				)
				(justify mirror)
			)
		)
		(property "Manufacturer" "Panasonic"
			(at 0 0 0)
			(layer "B.Fab")
			(hide yes)
			(effects
				(font
					(size 1 1)
					(thickness 0.15)
				)
				(justify mirror)
			)
		)
		(property "Tolerance" ""
			(at 0 0 0)
			(layer "B.Fab")
			(hide yes)
			(effects
				(font
					(size 1 1)
					(thickness 0.15)
				)
				(justify mirror)
			)
		)
		(property "Val" "0R"
			(at 0 0 0)
			(layer "B.Fab")
			(hide yes)
			(effects
				(font
					(size 1 1)
					(thickness 0.15)
				)
				(justify mirror)
			)
		)
		(sheetname "/Supply/")
		(sheetfile "supply.kicad_sch")
		(attr exclude_from_pos_files exclude_from_bom dnp)
		(fp_rect
			(start -0.93 0.47)
			(end 0.93 -0.47)
			(stroke
				(width 0.05)
				(type solid)
			)
			(fill no)
			(layer "B.CrtYd")
		)
		(fp_rect
			(start -0.5 0.25)
			(end 0.5 -0.25)
			(stroke
				(width 0.15)
				(type solid)
			)
			(fill no)
			(layer "B.Fab")
		)
		(pad "1" smd roundrect
			(at -0.485 0)
			(size 0.59 0.64)
			(layers "B.Cu" "B.Mask" "B.Paste")
			(roundrect_rratio 0.25)
			(net 1 "GND")
			(pintype "passive")
		)
		(pad "2" smd roundrect
			(at 0.485 0)
			(size 0.59 0.64)
			(layers "B.Cu" "B.Mask" "B.Paste")
			(roundrect_rratio 0.25)
			(net 209 "/Supply/FB5")
			(pintype "passive")
		)
	)
	(footprint "antmicro-footprints:R_0402_1005Metric"
		(layer "B.Cu")
		(at 137.777001 159.5755)
		(descr "Resistor SMD 0402")
		(tags "resistor SMD 0402")
		(property "Reference" "R130"
			(at -1.122484 0.772697 180)
			(layer "B.SilkS")
			(hide yes)
			(effects
				(font
					(size 0.7 0.7)
					(thickness 0.15)
				)
				(justify left bottom mirror)
			)
		)
		(property "Value" "R_1k_0402"
			(at -1.011843 -1.772047 180)
			(layer "B.Fab")
			(effects
				(font
					(size 0.7 0.7)
					(thickness 0.15)
				)
				(justify left bottom mirror)
			)
		)
		(property "Datasheet" "https://www.bourns.com/docs/product-datasheets/cr.pdf"
			(at 0 0 0)
			(layer "F.Fab")
			(hide yes)
			(effects
				(font
					(size 1.27 1.27)
					(thickness 0.15)
				)
			)
		)
		(property "Author" "Antmicro"
			(at 0 0 0)
			(layer "B.Fab")
			(hide yes)
			(effects
				(font
					(size 1 1)
					(thickness 0.15)
				)
				(justify mirror)
			)
		)
		(property "License" "Apache-2.0"
			(at 0 0 0)
			(layer "B.Fab")
			(hide yes)
			(effects
				(font
					(size 1 1)
					(thickness 0.15)
				)
				(justify mirror)
			)
		)
		(property "MPN" "CR0402-FX-1001GLF"
			(at 0 0 0)
			(layer "B.Fab")
			(hide yes)
			(effects
				(font
					(size 1 1)
					(thickness 0.15)
				)
				(justify mirror)
			)
		)
		(property "Manufacturer" "Bourns"
			(at 0 0 0)
			(layer "B.Fab")
			(hide yes)
			(effects
				(font
					(size 1 1)
					(thickness 0.15)
				)
				(justify mirror)
			)
		)
		(property "Tolerance" "1%"
			(at 0 0 0)
			(layer "B.Fab")
			(hide yes)
			(effects
				(font
					(size 1 1)
					(thickness 0.15)
				)
				(justify mirror)
			)
		)
		(property "Val" "1k"
			(at 0 0 0)
			(layer "B.Fab")
			(hide yes)
			(effects
				(font
					(size 1 1)
					(thickness 0.15)
				)
				(justify mirror)
			)
		)
		(sheetname "/FPGA banks HP/")
		(sheetfile "fpga-banks-32-34.kicad_sch")
		(attr smd)
		(fp_rect
			(start -0.93 0.47)
			(end 0.93 -0.47)
			(stroke
				(width 0.05)
				(type solid)
			)
			(fill no)
			(layer "B.CrtYd")
		)
		(fp_rect
			(start -0.5 0.25)
			(end 0.5 -0.25)
			(stroke
				(width 0.15)
				(type solid)
			)
			(fill no)
			(layer "B.Fab")
		)
		(pad "1" smd roundrect
			(at -0.485 0)
			(size 0.59 0.64)
			(layers "B.Cu" "B.Mask" "B.Paste")
			(roundrect_rratio 0.25)
			(net 1 "GND")
			(pintype "passive")
		)
		(pad "2" smd roundrect
			(at 0.485 0)
			(size 0.59 0.64)
			(layers "B.Cu" "B.Mask" "B.Paste")
			(roundrect_rratio 0.25)
			(net 379 "Net-(R129-Pad1)")
			(pintype "passive")
		)
	)
	(footprint "antmicro-footprints:TP_SMD_1mm"
		(layer "B.Cu")
		(at 172.3 184.4 180)
		(property "Reference" "TP67"
			(at 0.5 -0.4 0)
			(layer "B.SilkS")
			(effects
				(font
					(size 0.7 0.7)
					(thickness 0.15)
				)
				(justify left bottom mirror)
			)
		)
		(property "Value" "TP_1mm_SMD"
			(at 0 -1.4 0)
			(layer "B.Fab")
			(effects
				(font
					(size 0.7 0.7)
					(thickness 0.15)
				)
				(justify left bottom mirror)
			)
		)
		(property "MPN" ""
			(at 0 0 0)
			(unlocked yes)
			(layer "B.Fab")
			(hide yes)
			(effects
				(font
					(size 1 1)
					(thickness 0.15)
				)
				(justify mirror)
			)
		)
		(property "Manufacturer" ""
			(at 0 0 0)
			(unlocked yes)
			(layer "B.Fab")
			(hide yes)
			(effects
				(font
					(size 1 1)
					(thickness 0.15)
				)
				(justify mirror)
			)
		)
		(property "Author" "Antmicro"
			(at 0 0 0)
			(unlocked yes)
			(layer "B.Fab")
			(hide yes)
			(effects
				(font
					(size 1 1)
					(thickness 0.15)
				)
				(justify mirror)
			)
		)
		(property "License" "Apache-2.0"
			(at 0 0 0)
			(unlocked yes)
			(layer "B.Fab")
			(hide yes)
			(effects
				(font
					(size 1 1)
					(thickness 0.15)
				)
				(justify mirror)
			)
		)
		(sheetname "/I^{2}C/")
		(sheetfile "i2c.kicad_sch")
		(attr exclude_from_pos_files)
		(fp_circle
			(center 0 0)
			(end 0.6 0)
			(stroke
				(width 0.05)
				(type default)
			)
			(fill no)
			(layer "B.CrtYd")
		)
		(fp_text user "${REFERENCE}"
			(at -0.5 -2.8 0)
			(layer "B.Fab")
			(effects
				(font
					(size 0.7 0.7)
					(thickness 0.15)
				)
				(justify left bottom mirror)
			)
		)
		(fp_text user "Author: Antmicro"
			(at -0.5 -4 0)
			(layer "B.Fab")
			(effects
				(font
					(size 0.7 0.7)
					(thickness 0.15)
				)
				(justify left bottom mirror)
			)
		)
		(fp_text user "License: Apache-2.0"
			(at -0.5 -5.2 0)
			(layer "B.Fab")
			(effects
				(font
					(size 0.7 0.7)
					(thickness 0.15)
				)
				(justify left bottom mirror)
			)
		)
		(pad "1" smd circle
			(at 0 0 180)
			(size 1 1)
			(layers "B.Cu" "B.Mask")
			(net 760 "Net-(D18-A)")
			(pinfunction "1")
			(pintype "passive")
		)
	)
	(footprint "antmicro-footprints:C_0402_1005Metric"
		(layer "B.Cu")
		(at 147.875501 167.301)
		(descr "Capacitor SMD 0402 (1005 Metric), square (rectangular) end terminal, IPC_7351 nominal, (Body size source: IPC-SM-782 page 76, https://www.pcb-3d.com/wordpress/wp-content/uploads/ipc-sm-782a_amendment_1_and_2.pdf)")
		(tags "capacitor 0402")
		(property "Reference" "C94"
			(at 0 1.17 180)
			(layer "B.SilkS")
			(hide yes)
			(effects
				(font
					(size 0.7 0.7)
					(thickness 0.15)
				)
				(justify left bottom mirror)
			)
		)
		(property "Value" "C_100n_0402"
			(at 0 -1.169 180)
			(layer "B.Fab")
			(effects
				(font
					(size 0.7 0.7)
					(thickness 0.15)
				)
				(justify left bottom mirror)
			)
		)
		(property "Datasheet" "https://www.murata.com/products/productdetail?partno=GRM155R61H104KE14%23"
			(at 0 0 0)
			(layer "F.Fab")
			(hide yes)
			(effects
				(font
					(size 1.27 1.27)
					(thickness 0.15)
				)
			)
		)
		(property "Author" "Antmicro"
			(at 0 0 0)
			(layer "B.Fab")
			(hide yes)
			(effects
				(font
					(size 1 1)
					(thickness 0.15)
				)
				(justify mirror)
			)
		)
		(property "Dielectric" "X5R"
			(at 0 0 0)
			(layer "B.Fab")
			(hide yes)
			(effects
				(font
					(size 1 1)
					(thickness 0.15)
				)
				(justify mirror)
			)
		)
		(property "License" "Apache-2.0"
			(at 0 0 0)
			(layer "B.Fab")
			(hide yes)
			(effects
				(font
					(size 1 1)
					(thickness 0.15)
				)
				(justify mirror)
			)
		)
		(property "MPN" "GRM155R61H104KE14D"
			(at 0 0 0)
			(layer "B.Fab")
			(hide yes)
			(effects
				(font
					(size 1 1)
					(thickness 0.15)
				)
				(justify mirror)
			)
		)
		(property "Manufacturer" "Murata"
			(at 0 0 0)
			(layer "B.Fab")
			(hide yes)
			(effects
				(font
					(size 1 1)
					(thickness 0.15)
				)
				(justify mirror)
			)
		)
		(property "Val" "100n"
			(at 0 0 0)
			(layer "B.Fab")
			(hide yes)
			(effects
				(font
					(size 1 1)
					(thickness 0.15)
				)
				(justify mirror)
			)
		)
		(property "Voltage" "50V"
			(at 0 0 0)
			(layer "B.Fab")
			(hide yes)
			(effects
				(font
					(size 1 1)
					(thickness 0.15)
				)
				(justify mirror)
			)
		)
		(sheetname "/FPGA power/")
		(sheetfile "fpga-power.kicad_sch")
		(attr smd)
		(fp_rect
			(start -0.9656 0.4572)
			(end 0.9652 -0.4828)
			(stroke
				(width 0.05)
				(type solid)
			)
			(fill no)
			(layer "B.CrtYd")
		)
		(fp_line
			(start -0.5 -0.248)
			(end -0.5 0.25)
			(stroke
				(width 0.15)
				(type solid)
			)
			(layer "B.Fab")
		)
		(fp_line
			(start -0.5 0.25)
			(end 0.498 0.25)
			(stroke
				(width 0.15)
				(type solid)
			)
			(layer "B.Fab")
		)
		(fp_line
			(start 0.498 -0.248)
			(end -0.5 -0.248)
			(stroke
				(width 0.15)
				(type solid)
			)
			(layer "B.Fab")
		)
		(fp_line
			(start 0.498 0.25)
			(end 0.498 -0.248)
			(stroke
				(width 0.15)
				(type solid)
			)
			(layer "B.Fab")
		)
		(pad "1" smd roundrect
			(at -0.5 0 270)
			(size 0.6 0.6)
			(layers "B.Cu" "B.Mask" "B.Paste")
			(roundrect_rratio 0.25)
			(net 1 "GND")
			(pintype "passive")
		)
		(pad "2" smd roundrect
			(at 0.498 0)
			(size 0.6 0.6)
			(layers "B.Cu" "B.Mask" "B.Paste")
			(roundrect_rratio 0.25)
			(net 206 "+1V1")
			(pintype "passive")
		)
	)
)
